# S9S_MB_2U (Grand Teton) — schematic netlist excerpt (pin names and nets, part order shuffled) for the footprints in the layout excerpt that follows; sources: Cadence DE-HDL packaged netlist, KiCad conversion of 03242023_DA0F0TMBIJ0_F0T_Motherboard_J_brd_V01_OCP.brd

R3452  Q_RES  100K 1% CHIP  pkg 0402LF  page 149 : A = GPU_BASE_STBY_EN ; B = GND
PC1216  Q_CAP  22UF 16V 20% X6S  pkg C0805  page 262 : A = SW_P12V_AUX_P1V05_PCH_AUX_FLT ; B = GND
PR4224  Q_RES  0 5% CHIP  pkg 0402LF  page 274 : A = NC_PVCCINFAON_CPU0_ACSP6 ; B = GND

(kicad_pcb
	(version 20260206)
	(generator "pcbnew")
	(generator_version "10.0")
	(general
		(thickness 1.6)
		(legacy_teardrops no)
	)
	(paper "A4")
	(title_block
		(title "03242023_DA0F0TMBIJ0_F0T_Motherboard_J_brd_V01_OCP.brd")
		(comment 1 "Grand Teton / footprints 2415-2417 of 6105")
	)
	(layers
		(0 "F.Cu" signal "TOP")
		(4 "In1.Cu" signal "GND")
		(6 "In2.Cu" signal "IN1")
		(8 "In3.Cu" signal "GND1")
		(10 "In4.Cu" signal "IN2")
		(12 "In5.Cu" signal "GND2")
		(14 "In6.Cu" signal "IN3")
		(16 "In7.Cu" signal "GND3")
		(18 "In8.Cu" signal "VCC")
		(20 "In9.Cu" signal "VCC1")
		(22 "In10.Cu" signal "GND4")
		(24 "In11.Cu" signal "IN4")
		(26 "In12.Cu" signal "GND5")
		(28 "In13.Cu" signal "IN5")
		(30 "In14.Cu" signal "GND6")
		(32 "In15.Cu" signal "IN6")
		(34 "In16.Cu" signal "GND7")
		(2 "B.Cu" signal "BOTTOM")
		(9 "F.Adhes" user "F.Adhesive")
		(11 "B.Adhes" user "B.Adhesive")
		(13 "F.Paste" user "Package Geometry/Pastemask Top")
		(15 "B.Paste" user "Package Geometry/Pastemask Bottom")
		(5 "F.SilkS" user "Ref Des/Silkscreen Top")
		(7 "B.SilkS" user "Ref Des/Silkscreen Bottom")
		(1 "F.Mask" user "Board Geometry/Soldermask Top")
		(3 "B.Mask" user "Board Geometry/Soldermask Bottom")
		(17 "Dwgs.User" user "User.Drawings")
		(19 "Cmts.User" user "User.Comments")
		(21 "Eco1.User" user "User.Eco1")
		(23 "Eco2.User" user "User.Eco2")
		(25 "Edge.Cuts" user "Board Geometry/Outline")
		(27 "Margin" user)
		(31 "F.CrtYd" user "Package Geometry/Place Bound Top")
		(29 "B.CrtYd" user "Package Geometry/Place Bound Bottom")
		(35 "F.Fab" user "Ref Des/Assembly Top")
		(33 "B.Fab" user "Ref Des/Assembly Bottom")
	)
	(footprint ""
		(layer "F.Cu")
		(at 254.147828 -70.440296 -90)
		(property "Reference" "PC1216"
			(at 0 0 270)
			(layer "F.SilkS")
			(hide yes)
			(effects
				(font
					(size 1.27 1.27)
				)
			)
		)
		(property "Value" ""
			(at 0 0 270)
			(layer "F.Fab")
			(effects
				(font
					(size 1.27 1.27)
				)
			)
		)
		(duplicate_pad_numbers_are_jumpers no)
		(fp_line
			(start -1.524 0.762)
			(end -1.524 -0.762)
			(stroke
				(width 0.1524)
				(type default)
			)
			(layer "F.SilkS")
		)
		(fp_line
			(start 1.524 0.762)
			(end -1.524 0.762)
			(stroke
				(width 0.1524)
				(type default)
			)
			(layer "F.SilkS")
		)
		(fp_line
			(start -1.524 -0.762)
			(end 1.524 -0.762)
			(stroke
				(width 0.1524)
				(type default)
			)
			(layer "F.SilkS")
		)
		(fp_line
			(start 1.524 -0.762)
			(end 1.524 0.762)
			(stroke
				(width 0.1524)
				(type default)
			)
			(layer "F.SilkS")
		)
		(fp_line
			(start -1.1049 0.724916)
			(end 1.1049 0.724916)
			(stroke
				(width 0.1)
				(type default)
			)
			(layer "F.Fab")
		)
		(fp_line
			(start 1.1049 0.724916)
			(end 1.1049 -0.724916)
			(stroke
				(width 0.1)
				(type default)
			)
			(layer "F.Fab")
		)
		(fp_line
			(start -1.1049 -0.724916)
			(end -1.1049 0.724916)
			(stroke
				(width 0.1)
				(type default)
			)
			(layer "F.Fab")
		)
		(fp_line
			(start 1.1049 -0.724916)
			(end -1.1049 -0.724916)
			(stroke
				(width 0.1)
				(type default)
			)
			(layer "F.Fab")
		)
		(pad "1" smd rect
			(at -0.889 0 90)
			(size 1.016 1.27)
			(layers "F.Cu" "F.Mask" "F.Paste")
			(net "SW_P12V_AUX_P1V05_PCH_AUX_FLT")
		)
		(pad "2" smd rect
			(at 0.889 0 90)
			(size 1.016 1.27)
			(layers "F.Cu" "F.Mask" "F.Paste")
			(net "GND")
		)
	)
	(footprint ""
		(layer "F.Cu")
		(at 423.68216 -143.675608 90)
		(property "Reference" "PR4224"
			(at 0 0 90)
			(layer "F.SilkS")
			(hide yes)
			(effects
				(font
					(size 1.27 1.27)
				)
			)
		)
		(property "Value" ""
			(at 0 0 90)
			(layer "F.Fab")
			(effects
				(font
					(size 1.27 1.27)
				)
			)
		)
		(duplicate_pad_numbers_are_jumpers no)
		(fp_line
			(start 0.7874 -0.4064)
			(end 0.7874 0.4064)
			(stroke
				(width 0.1524)
				(type default)
			)
			(layer "F.SilkS")
		)
		(fp_line
			(start -0.7874 -0.4064)
			(end 0.7874 -0.4064)
			(stroke
				(width 0.1524)
				(type default)
			)
			(layer "F.SilkS")
		)
		(fp_line
			(start 0.7874 0.4064)
			(end -0.7874 0.4064)
			(stroke
				(width 0.1524)
				(type default)
			)
			(layer "F.SilkS")
		)
		(fp_line
			(start -0.7874 0.4064)
			(end -0.7874 -0.4064)
			(stroke
				(width 0.1524)
				(type default)
			)
			(layer "F.SilkS")
		)
		(fp_line
			(start -0.12065 -0.305054)
			(end -0.12065 -0.2794)
			(stroke
				(width 0.1)
				(type default)
			)
			(layer "F.Fab")
		)
		(fp_line
			(start -0.67945 -0.305054)
			(end -0.12065 -0.305054)
			(stroke
				(width 0.1)
				(type default)
			)
			(layer "F.Fab")
		)
		(fp_line
			(start 0.67945 -0.3048)
			(end 0.67945 0.3048)
			(stroke
				(width 0.1)
				(type default)
			)
			(layer "F.Fab")
		)
		(fp_line
			(start 0.12065 -0.3048)
			(end 0.67945 -0.3048)
			(stroke
				(width 0.1)
				(type default)
			)
			(layer "F.Fab")
		)
		(fp_line
			(start 0.12065 -0.2794)
			(end 0.12065 -0.3048)
			(stroke
				(width 0.1)
				(type default)
			)
			(layer "F.Fab")
		)
		(fp_line
			(start -0.12065 -0.2794)
			(end 0.12065 -0.2794)
			(stroke
				(width 0.1)
				(type default)
			)
			(layer "F.Fab")
		)
		(fp_line
			(start 0.120396 0.2794)
			(end -0.12065 0.2794)
			(stroke
				(width 0.1)
				(type default)
			)
			(layer "F.Fab")
		)
		(fp_line
			(start -0.12065 0.2794)
			(end -0.12065 0.3048)
			(stroke
				(width 0.1)
				(type default)
			)
			(layer "F.Fab")
		)
		(fp_line
			(start 0.67945 0.3048)
			(end 0.120396 0.3048)
			(stroke
				(width 0.1)
				(type default)
			)
			(layer "F.Fab")
		)
		(fp_line
			(start 0.120396 0.3048)
			(end 0.120396 0.2794)
			(stroke
				(width 0.1)
				(type default)
			)
			(layer "F.Fab")
		)
		(fp_line
			(start -0.12065 0.3048)
			(end -0.67945 0.3048)
			(stroke
				(width 0.1)
				(type default)
			)
			(layer "F.Fab")
		)
		(fp_line
			(start -0.67945 0.3048)
			(end -0.67945 -0.305054)
			(stroke
				(width 0.1)
				(type default)
			)
			(layer "F.Fab")
		)
		(pad "1" smd circle
			(at -0.40005 0 90)
			(size 0 0)
			(layers "F.Cu" "F.Mask" "F.Paste")
			(net "NC_PVCCINFAON_CPU0_ACSP6")
		)
		(pad "2" smd circle
			(at 0.40005 0 90)
			(size 0 0)
			(layers "F.Cu" "F.Mask" "F.Paste")
			(net "GND")
		)
	)
	(footprint ""
		(layer "F.Cu")
		(at 163.50488 -435.447948 180)
		(property "Reference" "R3452"
			(at 0 0 180)
			(layer "F.SilkS")
			(hide yes)
			(effects
				(font
					(size 1.27 1.27)
				)
			)
		)
		(property "Value" ""
			(at 0 0 180)
			(layer "F.Fab")
			(effects
				(font
					(size 1.27 1.27)
				)
			)
		)
		(duplicate_pad_numbers_are_jumpers no)
		(fp_line
			(start 0.7874 0.4064)
			(end -0.7874 0.4064)
			(stroke
				(width 0.1524)
				(type default)
			)
			(layer "F.SilkS")
		)
		(fp_line
			(start 0.7874 -0.4064)
			(end 0.7874 0.4064)
			(stroke
				(width 0.1524)
				(type default)
			)
			(layer "F.SilkS")
		)
		(fp_line
			(start -0.7874 0.4064)
			(end -0.7874 -0.4064)
			(stroke
				(width 0.1524)
				(type default)
			)
			(layer "F.SilkS")
		)
		(fp_line
			(start -0.7874 -0.4064)
			(end 0.7874 -0.4064)
			(stroke
				(width 0.1524)
				(type default)
			)
			(layer "F.SilkS")
		)
		(fp_line
			(start 0.67945 0.3048)
			(end 0.120396 0.3048)
			(stroke
				(width 0.1)
				(type default)
			)
			(layer "F.Fab")
		)
		(fp_line
			(start 0.67945 -0.3048)
			(end 0.67945 0.3048)
			(stroke
				(width 0.1)
				(type default)
			)
			(layer "F.Fab")
		)
		(fp_line
			(start 0.12065 -0.2794)
			(end 0.12065 -0.3048)
			(stroke
				(width 0.1)
				(type default)
			)
			(layer "F.Fab")
		)
		(fp_line
			(start 0.12065 -0.3048)
			(end 0.67945 -0.3048)
			(stroke
				(width 0.1)
				(type default)
			)
			(layer "F.Fab")
		)
		(fp_line
			(start 0.120396 0.3048)
			(end 0.120396 0.2794)
			(stroke
				(width 0.1)
				(type default)
			)
			(layer "F.Fab")
		)
		(fp_line
			(start 0.120396 0.2794)
			(end -0.12065 0.2794)
			(stroke
				(width 0.1)
				(type default)
			)
			(layer "F.Fab")
		)
		(fp_line
			(start -0.12065 0.3048)
			(end -0.67945 0.3048)
			(stroke
				(width 0.1)
				(type default)
			)
			(layer "F.Fab")
		)
		(fp_line
			(start -0.12065 0.2794)
			(end -0.12065 0.3048)
			(stroke
				(width 0.1)
				(type default)
			)
			(layer "F.Fab")
		)
		(fp_line
			(start -0.12065 -0.2794)
			(end 0.12065 -0.2794)
			(stroke
				(width 0.1)
				(type default)
			)
			(layer "F.Fab")
		)
		(fp_line
			(start -0.12065 -0.305054)
			(end -0.12065 -0.2794)
			(stroke
				(width 0.1)
				(type default)
			)
			(layer "F.Fab")
		)
		(fp_line
			(start -0.67945 0.3048)
			(end -0.67945 -0.305054)
			(stroke
				(width 0.1)
				(type default)
			)
			(layer "F.Fab")
		)
		(fp_line
			(start -0.67945 -0.305054)
			(end -0.12065 -0.305054)
			(stroke
				(width 0.1)
				(type default)
			)
			(layer "F.Fab")
		)
		(pad "1" smd circle
			(at -0.40005 0 180)
			(size 0 0)
			(layers "F.Cu" "F.Mask" "F.Paste")
			(net "GPU_BASE_STBY_EN")
		)
		(pad "2" smd circle
			(at 0.40005 0 180)
			(size 0 0)
			(layers "F.Cu" "F.Mask" "F.Paste")
			(net "GND")
		)
	)
)
